# BASEBOARD_FAB2 (Tioga Pass) — schematic parts with pin connectivity, parts 2401–2401 of 4751; source: Cadence DE-HDL packaged netlist (pstxprt.dat, pstxnet.dat, pstchip.dat)

J9M1  SCONN288_H44441003  SCONN  pkg PIP  page 84
  1  \12v\(1)  = P12V_NVDIMM_KLM
  2  VSS(93)  GROUND  = GND
  3  DQ(4)  BI  = M_K_DQ<4>
  4  VSS(92)  GROUND  = GND
  5  DQ(0)  BI  = M_K_DQ<0>
  6  VSS(91)  GROUND  = GND
  7  DQS9P  BI  = M_K_DQS_DP<9>
  8  DQS9N  BI  = M_K_DQS_DN<9>
  9  VSS(90)  GROUND  = GND
  10  DQ(6)  BI  = M_K_DQ<6>
  11  VSS(89)  GROUND  = GND
  12  DQ(2)  BI  = M_K_DQ<2>
  13  VSS(88)  GROUND  = GND
  14  DQ(12)  BI  = M_K_DQ<12>
  15  VSS(87)  GROUND  = GND
  16  DQ(8)  BI  = M_K_DQ<8>
  17  VSS(86)  GROUND  = GND
  18  DQS10P  BI  = M_K_DQS_DP<10>
  19  DQS10N  BI  = M_K_DQS_DN<10>
  20  VSS(85)  GROUND  = GND
  21  DQ(14)  BI  = M_K_DQ<14>
  22  VSS(84)  GROUND  = GND
  23  DQ(10)  BI  = M_K_DQ<10>
  24  VSS(83)  GROUND  = GND
  25  DQ(20)  BI  = M_K_DQ<20>
  26  VSS(82)  GROUND  = GND
  27  DQ(16)  BI  = M_K_DQ<16>
  28  VSS(81)  GROUND  = GND
  29  DQS11P  BI  = M_K_DQS_DP<11>
  30  DQS11N  BI  = M_K_DQS_DN<11>
  31  VSS(80)  GROUND  = GND
  32  DQ(22)  BI  = M_K_DQ<22>
  33  VSS(79)  GROUND  = GND
  34  DQ(18)  BI  = M_K_DQ<18>
  35  VSS(78)  GROUND  = GND
  36  DQ(28)  BI  = M_K_DQ<28>
  37  VSS(77)  GROUND  = GND
  38  DQ(24)  BI  = M_K_DQ<24>
  39  VSS(76)  GROUND  = GND
  40  DQS12P  BI  = M_K_DQS_DP<12>
  41  DQS12N  BI  = M_K_DQS_DN<12>
  42  VSS(75)  GROUND  = GND
  43  DQ(30)  BI  = M_K_DQ<30>
  44  VSS(74)  GROUND  = GND
  45  DQ(26)  BI  = M_K_DQ<26>
  46  VSS(73)  GROUND  = GND
  47  CB(4)  BI  = M_K_ECC<4>
  48  VSS(72)  GROUND  = GND
  49  CB(0)  BI  = M_K_ECC<0>
  50  VSS(71)  GROUND  = GND
  51  DQS17P  BI  = M_K_DQS_DP<17>
  52  DQS17N  BI  = M_K_DQS_DN<17>
  53  VSS(70)  GROUND  = GND
  54  CB(6)  BI  = M_K_ECC<6>
  55  VSS(69)  GROUND  = GND
  56  CB(2)  BI  = M_K_ECC<2>
  57  VSS(68)  GROUND  = GND
  58  RESET_N  BI  = M_KLM_RST_N
  59  VDD(25)  POWER  = PVDDQ_KLM
  60  CKE(0)  BI  = M_K_CKE<2>
  61  VDD(24)  POWER  = PVDDQ_KLM
  62  ACT_N  BI  = M_K_ACT_N
  63  BG(0)  BI  = M_K_BG<0>
  64  VDD(23)  POWER  = PVDDQ_KLM
  65  A12  BI  = M_K_MA<12>
  66  A9  BI  = M_K_MA<9>
  67  VDD(22)  POWER  = PVDDQ_KLM
  68  A8  BI  = M_K_MA<8>
  69  A6  BI  = M_K_MA<6>
  70  VDD(21)  POWER  = PVDDQ_KLM
  71  A3  BI  = M_K_MA<3>
  72  A1  BI  = M_K_MA<1>
  73  VDD(20)  POWER  = PVDDQ_KLM
  74  CK0P  BI  = M_K_CLK_DP<2>
  75  CK0N  BI  = M_K_CLK_DN<2>
  76  VDD(19)  POWER  = PVDDQ_KLM
  77  VTT(1)  POWER  = PVTT_KLM
  78  EVENT_N  BI  = FM_DIMM_EVENT_COD_N
  79  A0  BI  = M_K_MA<0>
  80  VDD(18)  POWER  = PVDDQ_KLM
  81  BA(0)  BI  = M_K_BA<0>
  82  A16_RAS_N  BI  = M_K_MA<16>
  83  VDD(17)  POWER  = PVDDQ_KLM
  84  S0_N  BI  = M_K_CS_N<4>
  85  VDD(16)  POWER  = PVDDQ_KLM
  86  A15_CAS_N  BI  = M_K_MA<15>
  87  ODT(0)  BI  = M_K_ODT<2>
  88  VDD(15)  POWER  = PVDDQ_KLM
  89  S1_N  BI  = M_K_CS_N<5>
  90  VDD(14)  POWER  = PVDDQ_KLM
  91  ODT(1)  BI  = M_K_ODT<3>
  92  VDD(13)  POWER  = PVDDQ_KLM
  93  S2_N_C(0)  BI  = M_K_CS_N<6>
  94  VSS(67)  GROUND  = GND
  95  DQ(36)  BI  = M_K_DQ<36>
  96  VSS(66)  GROUND  = GND
  97  DQ(32)  BI  = M_K_DQ<32>
  98  VSS(65)  GROUND  = GND
  99  DQS13P  BI  = M_K_DQS_DP<13>
  100  DQS13N  BI  = M_K_DQS_DN<13>
  101  VSS(64)  GROUND  = GND
  102  DQ(38)  BI  = M_K_DQ<38>
  103  VSS(63)  GROUND  = GND
  104  DQ(34)  BI  = M_K_DQ<34>
  105  VSS(62)  GROUND  = GND
  106  DQ(44)  BI  = M_K_DQ<44>
  107  VSS(61)  GROUND  = GND
  108  DQ(40)  BI  = M_K_DQ<40>
  109  VSS(60)  GROUND  = GND
  110  DQS14P  BI  = M_K_DQS_DP<14>
  111  DQS14N  BI  = M_K_DQS_DN<14>
  112  VSS(59)  GROUND  = GND
  113  DQ(46)  BI  = M_K_DQ<46>
  114  VSS(58)  GROUND  = GND
  115  DQ(42)  BI  = M_K_DQ<42>
  116  VSS(57)  GROUND  = GND
  117  DQ(52)  BI  = M_K_DQ<52>
  118  VSS(56)  GROUND  = GND
  119  DQ(48)  BI  = M_K_DQ<48>
  120  VSS(55)  GROUND  = GND
  121  DQS15P  BI  = M_K_DQS_DP<15>
  122  DQS15N  BI  = M_K_DQS_DN<15>
  123  VSS(54)  GROUND  = GND
  124  DQ(54)  BI  = M_K_DQ<54>
  125  VSS(53)  GROUND  = GND
  126  DQ(50)  BI  = M_K_DQ<50>
  127  VSS(52)  GROUND  = GND
  128  DQ(60)  BI  = M_K_DQ<60>
  129  VSS(51)  GROUND  = GND
  130  DQ(56)  BI  = M_K_DQ<56>
  131  VSS(50)  GROUND  = GND
  132  DQS16P  BI  = M_K_DQS_DP<16>
  133  DQS16N  BI  = M_K_DQS_DN<16>
  134  VSS(49)  GROUND  = GND
  135  DQ(62)  BI  = M_K_DQ<62>
  136  VSS(48)  GROUND  = GND
  137  DQ(58)  BI  = M_K_DQ<58>
  138  VSS(47)  GROUND  = GND
  139  SA(0)  BI  = PVPP_KLM
  140  SA(1)  BI  = GND
  141  SCL  BI  = SMB_DDR_KLM_VPP_SCL
  142  VPP(4)  POWER  = PVPP_KLM
  143  VPP(3)  POWER  = PVPP_KLM
  144  RFU(2)  BI  = TP_CH_K_DIMM0_RFU_2
  145  \12v\(0)  = P12V_NVDIMM_KLM
  146  VREFCA  BI  = M_K_VREF
  147  VSS(46)  GROUND  = GND
  148  DQ(5)  BI  = M_K_DQ<5>
  149  VSS(45)  GROUND  = GND
  150  DQ(1)  BI  = M_K_DQ<1>
  151  VSS(44)  GROUND  = GND
  152  DQS0N  BI  = M_K_DQS_DN<0>
  153  DQS0P  BI  = M_K_DQS_DP<0>
  154  VSS(43)  GROUND  = GND
  155  DQ(7)  BI  = M_K_DQ<7>
  156  VSS(42)  GROUND  = GND
  157  DQ(3)  BI  = M_K_DQ<3>
  158  VSS(41)  GROUND  = GND
  159  DQ(13)  BI  = M_K_DQ<13>
  160  VSS(40)  GROUND  = GND
  161  DQ(9)  BI  = M_K_DQ<9>
  162  VSS(39)  GROUND  = GND
  163  DQS1N  BI  = M_K_DQS_DN<1>
  164  DQS1P  BI  = M_K_DQS_DP<1>
  165  VSS(38)  GROUND  = GND
  166  DQ(15)  BI  = M_K_DQ<15>
  167  VSS(37)  GROUND  = GND
  168  DQ(11)  BI  = M_K_DQ<11>
  169  VSS(36)  GROUND  = GND
  170  DQ(21)  BI  = M_K_DQ<21>
  171  VSS(35)  GROUND  = GND
  172  DQ(17)  BI  = M_K_DQ<17>
  173  VSS(34)  GROUND  = GND
  174  DQS2N  BI  = M_K_DQS_DN<2>
  175  DQS2P  BI  = M_K_DQS_DP<2>
  176  VSS(33)  GROUND  = GND
  177  DQ(23)  BI  = M_K_DQ<23>
  178  VSS(32)  GROUND  = GND
  179  DQ(19)  BI  = M_K_DQ<19>
  180  VSS(31)  GROUND  = GND
  181  DQ(29)  BI  = M_K_DQ<29>
  182  VSS(30)  GROUND  = GND
  183  DQ(25)  BI  = M_K_DQ<25>
  184  VSS(29)  GROUND  = GND
  185  DQS3N  BI  = M_K_DQS_DN<3>
  186  DQS3P  BI  = M_K_DQS_DP<3>
  187  VSS(28)  GROUND  = GND
  188  DQ(31)  BI  = M_K_DQ<31>
  189  VSS(27)  GROUND  = GND
  190  DQ(27)  BI  = M_K_DQ<27>
  191  VSS(26)  GROUND  = GND
  192  CB(5)  BI  = M_K_ECC<5>
  193  VSS(25)  GROUND  = GND
  194  CB(1)  BI  = M_K_ECC<1>
  195  VSS(24)  GROUND  = GND
  196  DQS8N  BI  = M_K_DQS_DN<8>
  197  DQS8P  BI  = M_K_DQS_DP<8>
  198  VSS(23)  GROUND  = GND
  199  CB(7)  BI  = M_K_ECC<7>
  200  VSS(22)  GROUND  = GND
  201  CB(3)  BI  = M_K_ECC<3>
  202  VSS(21)  GROUND  = GND
  203  CKE(1)  BI  = M_K_CKE<3>
  204  VDD(12)  POWER  = PVDDQ_KLM
  205  RFU(0)  BI  = TP_CH_K_DIMM0_RFU_0
  206  VDD(11)  POWER  = PVDDQ_KLM
  207  BG(1)  BI  = M_K_BG<1>
  208  ALERT_N  BI  = M_K_ALERT_N
  209  VDD(10)  POWER  = PVDDQ_KLM
  210  A11  BI  = M_K_MA<11>
  211  A7  BI  = M_K_MA<7>
  212  VDD(9)  POWER  = PVDDQ_KLM
  213  A5  BI  = M_K_MA<5>
  214  A4  BI  = M_K_MA<4>
  215  VDD(8)  POWER  = PVDDQ_KLM
  216  A2  BI  = M_K_MA<2>
  217  VDD(7)  POWER  = PVDDQ_KLM
  218  CK1P  BI  = M_K_CLK_DP<3>
  219  CK1N  BI  = M_K_CLK_DN<3>
  220  VDD(6)  POWER  = PVDDQ_KLM
  221  VTT(0)  POWER  = PVTT_KLM
  222  PAR  BI  = M_K_PAR
  223  VDD(5)  POWER  = PVDDQ_KLM
  224  BA(1)  BI  = M_K_BA<1>
  225  A10  BI  = M_K_MA<10>
  226  VDD(4)  POWER  = PVDDQ_KLM
  227  RFU(1)  BI  = TP_CH_K_DIMM0_RFU_1
  228  A14_WE_N  BI  = M_K_MA<14>
  229  VDD(3)  POWER  = PVDDQ_KLM
  230  SAVE_N_NC  BI  = FM_ADR_COMPLETE_KLM_N
  231  VDD(2)  POWER  = PVDDQ_KLM
  232  A13  BI  = M_K_MA<13>
  233  VDD(1)  POWER  = PVDDQ_KLM
  234  A17  BI  = M_K_MA<17>
  235  C(2)  BI  = M_K_C<2>
  236  VDD(0)  POWER  = PVDDQ_KLM
  237  S3_N_C(1)  BI  = M_K_CS_N<7>
  238  SA(2)  BI  = GND
  239  VSS(20)  GROUND  = GND
  240  DQ(37)  BI  = M_K_DQ<37>
  241  VSS(19)  GROUND  = GND
  242  DQ(33)  BI  = M_K_DQ<33>
  243  VSS(18)  GROUND  = GND
  244  DQS4N  BI  = M_K_DQS_DN<4>
  245  DQS4P  BI  = M_K_DQS_DP<4>
  246  VSS(17)  GROUND  = GND
  247  DQ(39)  BI  = M_K_DQ<39>
  248  VSS(16)  GROUND  = GND
  249  DQ(35)  BI  = M_K_DQ<35>
  250  VSS(15)  GROUND  = GND
  251  DQ(45)  BI  = M_K_DQ<45>
  252  VSS(14)  GROUND  = GND
  253  DQ(41)  BI  = M_K_DQ<41>
  254  VSS(13)  GROUND  = GND
  255  DQS5N  BI  = M_K_DQS_DN<5>
  256  DQS5P  BI  = M_K_DQS_DP<5>
  257  VSS(12)  GROUND  = GND
  258  DQ(47)  BI  = M_K_DQ<47>
  259  VSS(11)  GROUND  = GND
  260  DQ(43)  BI  = M_K_DQ<43>
  261  VSS(10)  GROUND  = GND
  262  DQ(53)  BI  = M_K_DQ<53>
  263  VSS(9)  GROUND  = GND
  264  DQ(49)  BI  = M_K_DQ<49>
  265  VSS(8)  GROUND  = GND
  266  DQS6N  BI  = M_K_DQS_DN<6>
  267  DQS6P  BI  = M_K_DQS_DP<6>
  268  VSS(7)  GROUND  = GND
  269  DQ(55)  BI  = M_K_DQ<55>
  270  VSS(6)  GROUND  = GND
  271  DQ(51)  BI  = M_K_DQ<51>
  272  VSS(5)  GROUND  = GND
  273  DQ(61)  BI  = M_K_DQ<61>
  274  VSS(4)  GROUND  = GND
  275  DQ(57)  BI  = M_K_DQ<57>
  276  VSS(3)  GROUND  = GND
  277  DQS7N  BI  = M_K_DQS_DN<7>
  278  DQS7P  BI  = M_K_DQS_DP<7>
  279  VSS(2)  GROUND  = GND
  280  DQ(63)  BI  = M_K_DQ<63>
  281  VSS(1)  GROUND  = GND
  282  DQ(59)  BI  = M_K_DQ<59>
  283  VSS(0)  GROUND  = GND
  284  VDDSPD  BI  = PVPP_KLM
  285  SDA  BI  = SMB_DDR_KLM_VPP_SDA
  286  VPP(1)  POWER  = PVPP_KLM
  287  VPP(0)  POWER  = PVPP_KLM
  288  VPP(2)  POWER  = PVPP_KLM
